# T6G (Grand Teton) — schematic netlist excerpt (pin names and nets, part order shuffled) for the footprints in the layout excerpt that follows; sources: Cadence DE-HDL packaged netlist, KiCad conversion of 04192023_DAF0TMB3IC0_F0TG_MB_C_brd_V02_OCP.brd

R1493  Q_RES  10K 5% CHIP  pkg 0402LF  page 188 : A = P1V8_AUX ; B = PWRGD_P3V3_R1
R85  Q_RES  0 5% CHIP  pkg 0402LF  page 238 : A = SMB_FRU_3V3AUX_SCL ; B = SMB_FRU_3V3AUX_R1_SCL

(kicad_pcb
	(version 20260206)
	(generator "pcbnew")
	(generator_version "10.0")
	(general
		(thickness 1.6)
		(legacy_teardrops no)
	)
	(paper "A4")
	(title_block
		(title "04192023_DAF0TMB3IC0_F0TG_MB_C_brd_V02_OCP.brd")
		(comment 1 "Grand Teton / footprints 1395-1396 of 8354")
	)
	(layers
		(0 "F.Cu" signal "TOP")
		(4 "In1.Cu" signal "GND")
		(6 "In2.Cu" signal "IN1")
		(8 "In3.Cu" signal "GND1")
		(10 "In4.Cu" signal "IN2")
		(12 "In5.Cu" signal "GND2")
		(14 "In6.Cu" signal "IN3")
		(16 "In7.Cu" signal "GND3")
		(18 "In8.Cu" signal "VCC")
		(20 "In9.Cu" signal "VCC1")
		(22 "In10.Cu" signal "GND4")
		(24 "In11.Cu" signal "IN4")
		(26 "In12.Cu" signal "GND5")
		(28 "In13.Cu" signal "IN5")
		(30 "In14.Cu" signal "GND6")
		(32 "In15.Cu" signal "IN6")
		(34 "In16.Cu" signal "GND7")
		(2 "B.Cu" signal "BOTTOM")
		(9 "F.Adhes" user "F.Adhesive")
		(11 "B.Adhes" user "B.Adhesive")
		(13 "F.Paste" user "Package Geometry/Pastemask Top")
		(15 "B.Paste" user "Package Geometry/Pastemask Bottom")
		(5 "F.SilkS" user "Ref Des/Silkscreen Top")
		(7 "B.SilkS" user "Ref Des/Silkscreen Bottom")
		(1 "F.Mask" user "Board Geometry/Soldermask Top")
		(3 "B.Mask" user "Board Geometry/Soldermask Bottom")
		(17 "Dwgs.User" user "User.Drawings")
		(19 "Cmts.User" user "User.Comments")
		(21 "Eco1.User" user "User.Eco1")
		(23 "Eco2.User" user "User.Eco2")
		(25 "Edge.Cuts" user "Board Geometry/Outline")
		(27 "Margin" user)
		(31 "F.CrtYd" user "Package Geometry/Place Bound Top")
		(29 "B.CrtYd" user "Package Geometry/Place Bound Bottom")
		(35 "F.Fab" user "Ref Des/Assembly Top")
		(33 "B.Fab" user "Ref Des/Assembly Bottom")
	)
	(footprint ""
		(layer "F.Cu")
		(at 317.896748 -116.378228 180)
		(property "Reference" "R85"
			(at 0 0 180)
			(layer "F.SilkS")
			(hide yes)
			(effects
				(font
					(size 1.27 1.27)
				)
			)
		)
		(property "Value" ""
			(at 0 0 180)
			(layer "F.Fab")
			(effects
				(font
					(size 1.27 1.27)
				)
			)
		)
		(duplicate_pad_numbers_are_jumpers no)
		(fp_line
			(start 0.7874 0.4064)
			(end -0.7874 0.4064)
			(stroke
				(width 0.1524)
				(type default)
			)
			(layer "F.SilkS")
		)
		(fp_line
			(start 0.7874 -0.4064)
			(end 0.7874 0.4064)
			(stroke
				(width 0.1524)
				(type default)
			)
			(layer "F.SilkS")
		)
		(fp_line
			(start -0.7874 0.4064)
			(end -0.7874 -0.4064)
			(stroke
				(width 0.1524)
				(type default)
			)
			(layer "F.SilkS")
		)
		(fp_line
			(start -0.7874 -0.4064)
			(end 0.7874 -0.4064)
			(stroke
				(width 0.1524)
				(type default)
			)
			(layer "F.SilkS")
		)
		(fp_line
			(start 0.67945 0.3048)
			(end 0.120396 0.3048)
			(stroke
				(width 0.1)
				(type default)
			)
			(layer "F.Fab")
		)
		(fp_line
			(start 0.67945 -0.3048)
			(end 0.67945 0.3048)
			(stroke
				(width 0.1)
				(type default)
			)
			(layer "F.Fab")
		)
		(fp_line
			(start 0.12065 -0.2794)
			(end 0.12065 -0.3048)
			(stroke
				(width 0.1)
				(type default)
			)
			(layer "F.Fab")
		)
		(fp_line
			(start 0.12065 -0.3048)
			(end 0.67945 -0.3048)
			(stroke
				(width 0.1)
				(type default)
			)
			(layer "F.Fab")
		)
		(fp_line
			(start 0.120396 0.3048)
			(end 0.120396 0.2794)
			(stroke
				(width 0.1)
				(type default)
			)
			(layer "F.Fab")
		)
		(fp_line
			(start 0.120396 0.2794)
			(end -0.12065 0.2794)
			(stroke
				(width 0.1)
				(type default)
			)
			(layer "F.Fab")
		)
		(fp_line
			(start -0.12065 0.3048)
			(end -0.67945 0.3048)
			(stroke
				(width 0.1)
				(type default)
			)
			(layer "F.Fab")
		)
		(fp_line
			(start -0.12065 0.2794)
			(end -0.12065 0.3048)
			(stroke
				(width 0.1)
				(type default)
			)
			(layer "F.Fab")
		)
		(fp_line
			(start -0.12065 -0.2794)
			(end 0.12065 -0.2794)
			(stroke
				(width 0.1)
				(type default)
			)
			(layer "F.Fab")
		)
		(fp_line
			(start -0.12065 -0.305054)
			(end -0.12065 -0.2794)
			(stroke
				(width 0.1)
				(type default)
			)
			(layer "F.Fab")
		)
		(fp_line
			(start -0.67945 0.3048)
			(end -0.67945 -0.305054)
			(stroke
				(width 0.1)
				(type default)
			)
			(layer "F.Fab")
		)
		(fp_line
			(start -0.67945 -0.305054)
			(end -0.12065 -0.305054)
			(stroke
				(width 0.1)
				(type default)
			)
			(layer "F.Fab")
		)
		(pad "1" smd circle
			(at -0.40005 0 180)
			(size 0 0)
			(layers "F.Cu" "F.Mask" "F.Paste")
			(net "SMB_FRU_3V3AUX_SCL")
		)
		(pad "2" smd circle
			(at 0.40005 0 180)
			(size 0 0)
			(layers "F.Cu" "F.Mask" "F.Paste")
			(net "SMB_FRU_3V3AUX_R1_SCL")
		)
	)
	(footprint ""
		(layer "F.Cu")
		(at 107.895136 -127.748538 -90)
		(property "Reference" "R1493"
			(at 0 0 270)
			(layer "F.SilkS")
			(hide yes)
			(effects
				(font
					(size 1.27 1.27)
				)
			)
		)
		(property "Value" ""
			(at 0 0 270)
			(layer "F.Fab")
			(effects
				(font
					(size 1.27 1.27)
				)
			)
		)
		(duplicate_pad_numbers_are_jumpers no)
		(fp_line
			(start -0.7874 0.4064)
			(end -0.7874 -0.4064)
			(stroke
				(width 0.1524)
				(type default)
			)
			(layer "F.SilkS")
		)
		(fp_line
			(start 0.7874 0.4064)
			(end -0.7874 0.4064)
			(stroke
				(width 0.1524)
				(type default)
			)
			(layer "F.SilkS")
		)
		(fp_line
			(start -0.7874 -0.4064)
			(end 0.7874 -0.4064)
			(stroke
				(width 0.1524)
				(type default)
			)
			(layer "F.SilkS")
		)
		(fp_line
			(start 0.7874 -0.4064)
			(end 0.7874 0.4064)
			(stroke
				(width 0.1524)
				(type default)
			)
			(layer "F.SilkS")
		)
		(fp_line
			(start -0.67945 0.3048)
			(end -0.67945 -0.305054)
			(stroke
				(width 0.1)
				(type default)
			)
			(layer "F.Fab")
		)
		(fp_line
			(start -0.12065 0.3048)
			(end -0.67945 0.3048)
			(stroke
				(width 0.1)
				(type default)
			)
			(layer "F.Fab")
		)
		(fp_line
			(start 0.120396 0.3048)
			(end 0.120396 0.2794)
			(stroke
				(width 0.1)
				(type default)
			)
			(layer "F.Fab")
		)
		(fp_line
			(start 0.67945 0.3048)
			(end 0.120396 0.3048)
			(stroke
				(width 0.1)
				(type default)
			)
			(layer "F.Fab")
		)
		(fp_line
			(start -0.12065 0.2794)
			(end -0.12065 0.3048)
			(stroke
				(width 0.1)
				(type default)
			)
			(layer "F.Fab")
		)
		(fp_line
			(start 0.120396 0.2794)
			(end -0.12065 0.2794)
			(stroke
				(width 0.1)
				(type default)
			)
			(layer "F.Fab")
		)
		(fp_line
			(start -0.12065 -0.2794)
			(end 0.12065 -0.2794)
			(stroke
				(width 0.1)
				(type default)
			)
			(layer "F.Fab")
		)
		(fp_line
			(start 0.12065 -0.2794)
			(end 0.12065 -0.3048)
			(stroke
				(width 0.1)
				(type default)
			)
			(layer "F.Fab")
		)
		(fp_line
			(start 0.12065 -0.3048)
			(end 0.67945 -0.3048)
			(stroke
				(width 0.1)
				(type default)
			)
			(layer "F.Fab")
		)
		(fp_line
			(start 0.67945 -0.3048)
			(end 0.67945 0.3048)
			(stroke
				(width 0.1)
				(type default)
			)
			(layer "F.Fab")
		)
		(fp_line
			(start -0.67945 -0.305054)
			(end -0.12065 -0.305054)
			(stroke
				(width 0.1)
				(type default)
			)
			(layer "F.Fab")
		)
		(fp_line
			(start -0.12065 -0.305054)
			(end -0.12065 -0.2794)
			(stroke
				(width 0.1)
				(type default)
			)
			(layer "F.Fab")
		)
		(pad "1" smd circle
			(at -0.40005 0 270)
			(size 0 0)
			(layers "F.Cu" "F.Mask" "F.Paste")
			(net "P1V8_AUX")
		)
		(pad "2" smd circle
			(at 0.40005 0 270)
			(size 0 0)
			(layers "F.Cu" "F.Mask" "F.Paste")
			(net "PWRGD_P3V3_R1")
		)
	)
)
